(kicad_pcb
	(version 20260206)
	(generator "pcbnew")
	(generator_version "10.0")
	(general
		(thickness 1.6)
		(legacy_teardrops no)
	)
	(paper "A4")
	(title_block
		(title "Wiwynn_Tioga_Pass_MB.brd")
		(comment 1 "Tioga Pass / footprints 455-461 of 4770")
	)
	(layers
		(0 "F.Cu" signal "TOP")
		(4 "In1.Cu" signal "L2GND")
		(6 "In2.Cu" signal "L3")
		(8 "In3.Cu" signal "L4GND")
		(10 "In4.Cu" signal "L5")
		(12 "In5.Cu" signal "L6GND")
		(14 "In6.Cu" signal "L7VCC")
		(16 "In7.Cu" signal "L8VCC")
		(18 "In8.Cu" signal "L9GND")
		(20 "In9.Cu" signal "L10")
		(22 "In10.Cu" signal "L11GND")
		(24 "In11.Cu" signal "L12")
		(26 "In12.Cu" signal "L13GND")
		(2 "B.Cu" signal "BOTTOM")
		(9 "F.Adhes" user "F.Adhesive")
		(11 "B.Adhes" user "B.Adhesive")
		(13 "F.Paste" user "Package Geometry/Pastemask Top")
		(15 "B.Paste" user "Package Geometry/Pastemask Bottom")
		(5 "F.SilkS" user "Ref Des/Silkscreen Top")
		(7 "B.SilkS" user "Ref Des/Silkscreen Bottom")
		(1 "F.Mask" user "Board Geometry/Soldermask Top")
		(3 "B.Mask" user "Board Geometry/Soldermask Bottom")
		(17 "Dwgs.User" user "User.Drawings")
		(19 "Cmts.User" user "User.Comments")
		(21 "Eco1.User" user "User.Eco1")
		(23 "Eco2.User" user "User.Eco2")
		(25 "Edge.Cuts" user "Board Geometry/Outline")
		(27 "Margin" user)
		(31 "F.CrtYd" user "Package Geometry/Place Bound Top")
		(29 "B.CrtYd" user "Package Geometry/Place Bound Bottom")
		(35 "F.Fab" user "Ref Des/Assembly Top")
		(33 "B.Fab" user "Ref Des/Assembly Bottom")
	)
	(footprint ""
		(layer "F.Cu")
		(at 172.0469 -6.9342 -90)
		(property "Reference" "R4G15"
			(at 0 0 270)
			(layer "F.SilkS")
			(hide yes)
			(effects
				(font
					(size 1.27 1.27)
				)
			)
		)
		(property "Value" ""
			(at 0 0 270)
			(layer "F.Fab")
			(effects
				(font
					(size 1.27 1.27)
				)
			)
		)
		(duplicate_pad_numbers_are_jumpers no)
		(fp_poly
			(pts
				(xy -0.2794 -0.1016) (xy 0.2794 -0.1016) (xy 0.2794 0.9906) (xy -0.2794 0.9906)
			)
			(stroke
				(width 0)
				(type default)
			)
			(fill no)
			(layer "F.CrtYd")
		)
		(fp_line
			(start -0.2794 0.9906)
			(end 0.2794 0.9906)
			(stroke
				(width 0.1)
				(type default)
			)
			(layer "F.Fab")
		)
		(fp_line
			(start 0.2794 0.9906)
			(end 0.2794 -0.1016)
			(stroke
				(width 0.1)
				(type default)
			)
			(layer "F.Fab")
		)
		(fp_line
			(start -0.2794 -0.1016)
			(end -0.2794 0.9906)
			(stroke
				(width 0.1)
				(type default)
			)
			(layer "F.Fab")
		)
		(fp_line
			(start 0.2794 -0.1016)
			(end -0.2794 -0.1016)
			(stroke
				(width 0.1)
				(type default)
			)
			(layer "F.Fab")
		)
		(pad "1" smd rect
			(at 0 0 270)
			(size 0.508 0.508)
			(layers "F.Cu" "F.Mask" "F.Paste")
			(net "PWRGD_PVTT_GHJ_CPU1_R")
		)
		(pad "2" smd rect
			(at 0 0.889 270)
			(size 0.508 0.508)
			(layers "F.Cu" "F.Mask" "F.Paste")
			(net "PWRGD_PVTT_CPU1")
		)
		(zone
			(layer "F.Cu")
			(hatch none 0.5)
			(connect_pads
				(clearance 0)
			)
			(min_thickness 0.25)
			(keepout
				(tracks not_allowed)
				(vias allowed)
				(pads allowed)
				(copperpour not_allowed)
				(footprints allowed)
			)
			(placement
				(enabled no)
				(sheetname "")
			)
			(fill
				(thermal_gap 0.5)
				(thermal_bridge_width 0.5)
				(island_removal_mode 0)
			)
			(polygon
				(pts
					(xy 171.4119 -7.1882) (xy 171.4119 -6.6802) (xy 171.7929 -6.6802) (xy 171.7929 -7.1882)
				)
			)
		)
		(zone
			(layer "F.Cu")
			(hatch none 0.5)
			(connect_pads
				(clearance 0)
			)
			(min_thickness 0.25)
			(keepout
				(tracks allowed)
				(vias not_allowed)
				(pads allowed)
				(copperpour not_allowed)
				(footprints allowed)
			)
			(placement
				(enabled no)
				(sheetname "")
			)
			(fill
				(thermal_gap 0.5)
				(thermal_bridge_width 0.5)
				(island_removal_mode 0)
			)
			(polygon
				(pts
					(xy 171.7929 -7.1882) (xy 171.7929 -6.6802) (xy 171.4119 -6.6802) (xy 171.4119 -7.1882)
				)
			)
		)
	)
	(footprint ""
		(layer "F.Cu")
		(at 402.641054 -43.729148 90)
		(property "Reference" "R1T35"
			(at 0 0 90)
			(layer "F.SilkS")
			(hide yes)
			(effects
				(font
					(size 1.27 1.27)
				)
			)
		)
		(property "Value" ""
			(at 0 0 90)
			(layer "F.Fab")
			(effects
				(font
					(size 1.27 1.27)
				)
			)
		)
		(duplicate_pad_numbers_are_jumpers no)
		(fp_poly
			(pts
				(xy -0.2794 -0.1016) (xy 0.2794 -0.1016) (xy 0.2794 0.9906) (xy -0.2794 0.9906)
			)
			(stroke
				(width 0)
				(type default)
			)
			(fill no)
			(layer "F.CrtYd")
		)
		(fp_line
			(start 0.2794 -0.1016)
			(end -0.2794 -0.1016)
			(stroke
				(width 0.1)
				(type default)
			)
			(layer "F.Fab")
		)
		(fp_line
			(start -0.2794 -0.1016)
			(end -0.2794 0.9906)
			(stroke
				(width 0.1)
				(type default)
			)
			(layer "F.Fab")
		)
		(fp_line
			(start 0.2794 0.9906)
			(end 0.2794 -0.1016)
			(stroke
				(width 0.1)
				(type default)
			)
			(layer "F.Fab")
		)
		(fp_line
			(start -0.2794 0.9906)
			(end 0.2794 0.9906)
			(stroke
				(width 0.1)
				(type default)
			)
			(layer "F.Fab")
		)
		(pad "1" smd rect
			(at 0 0 90)
			(size 0.508 0.508)
			(layers "F.Cu" "F.Mask" "F.Paste")
			(net "FM_CPU0_PROCHOT_LVT3_N")
		)
		(pad "2" smd rect
			(at 0 0.889 90)
			(size 0.508 0.508)
			(layers "F.Cu" "F.Mask" "F.Paste")
			(net "FM_CPU0_PROCHOT_PCH_N")
		)
		(zone
			(layer "F.Cu")
			(hatch none 0.5)
			(connect_pads
				(clearance 0)
			)
			(min_thickness 0.25)
			(keepout
				(tracks allowed)
				(vias not_allowed)
				(pads allowed)
				(copperpour not_allowed)
				(footprints allowed)
			)
			(placement
				(enabled no)
				(sheetname "")
			)
			(fill
				(thermal_gap 0.5)
				(thermal_bridge_width 0.5)
				(island_removal_mode 0)
			)
			(polygon
				(pts
					(xy 402.895054 -43.475148) (xy 402.895054 -43.983148) (xy 403.276054 -43.983148) (xy 403.276054 -43.475148)
				)
			)
		)
		(zone
			(layer "F.Cu")
			(hatch none 0.5)
			(connect_pads
				(clearance 0)
			)
			(min_thickness 0.25)
			(keepout
				(tracks not_allowed)
				(vias allowed)
				(pads allowed)
				(copperpour not_allowed)
				(footprints allowed)
			)
			(placement
				(enabled no)
				(sheetname "")
			)
			(fill
				(thermal_gap 0.5)
				(thermal_bridge_width 0.5)
				(island_removal_mode 0)
			)
			(polygon
				(pts
					(xy 403.276054 -43.475148) (xy 403.276054 -43.983148) (xy 402.895054 -43.983148) (xy 402.895054 -43.475148)
				)
			)
		)
	)
	(footprint ""
		(layer "F.Cu")
		(at 188.98108 -65.27038 180)
		(property "Reference" "CF1"
			(at 0 0 180)
			(layer "F.SilkS")
			(hide yes)
			(effects
				(font
					(size 1.27 1.27)
				)
			)
		)
		(property "Value" "*"
			(at 1.1811 -2.8194 180)
			(unlocked yes)
			(layer "F.Fab")
			(hide yes)
			(effects
				(font
					(size 1.27 1.016)
					(thickness 0.1524)
				)
			)
		)
		(property "Device Type" "SC22P50V2JN-4GP_SMD-BCG-SC22P5A"
			(at 1.1811 -4.3434 180)
			(unlocked yes)
			(layer "F.Fab")
			(hide yes)
			(effects
				(font
					(size 1.27 1.016)
					(thickness 0.1524)
				)
			)
		)
		(duplicate_pad_numbers_are_jumpers no)
		(fp_rect
			(start -0.4318 0.9525)
			(end 0.4318 -0.9525)
			(stroke
				(width 0)
				(type default)
			)
			(fill no)
			(layer "F.CrtYd")
		)
		(fp_rect
			(start -0.4318 0.9525)
			(end 0.4318 -0.9525)
			(stroke
				(width 0)
				(type default)
			)
			(fill no)
			(layer "F.Fab")
		)
		(pad "1" smd custom
			(at 0 -0.4445 180)
			(size 0.1524 0.1524)
			(layers "F.Cu" "F.Mask" "F.Paste")
			(net "VR_PVCCIN_CPU0_AIREF1")
			(options
				(clearance outline)
				(anchor circle)
			)
			(primitives
				(gr_poly
					(pts
						(arc
							(start 0.3048 -0.2032)
							(mid 0.275042 -0.275042)
							(end 0.2032 -0.3048)
						)
						(arc
							(start -0.2032 -0.3048)
							(mid -0.275042 -0.275042)
							(end -0.3048 -0.2032)
						)
						(arc
							(start -0.3048 0.2032)
							(mid -0.275042 0.275042)
							(end -0.2032 0.3048)
						)
						(arc
							(start 0.2032 0.3048)
							(mid 0.275042 0.275042)
							(end 0.3048 0.2032)
						)
					)
					(width 0)
					(fill yes)
				)
			)
		)
		(pad "2" smd custom
			(at 0 0.4445 180)
			(size 0.1524 0.1524)
			(layers "F.Cu" "F.Mask" "F.Paste")
			(net "ISENSE_PVCCIN_CPU0_PH1_IMON")
			(options
				(clearance outline)
				(anchor circle)
			)
			(primitives
				(gr_poly
					(pts
						(arc
							(start 0.3048 -0.2032)
							(mid 0.275042 -0.275042)
							(end 0.2032 -0.3048)
						)
						(arc
							(start -0.2032 -0.3048)
							(mid -0.275042 -0.275042)
							(end -0.3048 -0.2032)
						)
						(arc
							(start -0.3048 0.2032)
							(mid -0.275042 0.275042)
							(end -0.2032 0.3048)
						)
						(arc
							(start 0.2032 0.3048)
							(mid 0.275042 0.275042)
							(end 0.3048 0.2032)
						)
					)
					(width 0)
					(fill yes)
				)
			)
		)
	)
	(footprint ""
		(layer "F.Cu")
		(at 181.1147 -76.52385 -90)
		(property "Reference" "C4D15"
			(at 0 0 270)
			(layer "F.SilkS")
			(hide yes)
			(effects
				(font
					(size 1.27 1.27)
				)
			)
		)
		(property "Value" ""
			(at 0 0 270)
			(layer "F.Fab")
			(effects
				(font
					(size 1.27 1.27)
				)
			)
		)
		(duplicate_pad_numbers_are_jumpers no)
		(fp_poly
			(pts
				(xy 0.3048 -0.1016) (xy 0.3048 0.9906) (xy -0.3048 0.9906) (xy -0.3048 -0.1016)
			)
			(stroke
				(width 0)
				(type default)
			)
			(fill no)
			(layer "F.CrtYd")
		)
		(fp_line
			(start -0.3048 0.9906)
			(end 0.3048 0.9906)
			(stroke
				(width 0.1)
				(type default)
			)
			(layer "F.Fab")
		)
		(fp_line
			(start 0.3048 0.9906)
			(end 0.3048 -0.1016)
			(stroke
				(width 0.1)
				(type default)
			)
			(layer "F.Fab")
		)
		(fp_line
			(start -0.3048 -0.1016)
			(end -0.3048 0.9906)
			(stroke
				(width 0.1)
				(type default)
			)
			(layer "F.Fab")
		)
		(fp_line
			(start 0.3048 -0.1016)
			(end -0.3048 -0.1016)
			(stroke
				(width 0.1)
				(type default)
			)
			(layer "F.Fab")
		)
		(pad "1" smd rect
			(at 0 0 270)
			(size 0.508 0.508)
			(layers "F.Cu" "F.Mask" "F.Paste")
			(net "VR_PVCCIN_CPU0_VDD")
		)
		(pad "2" smd rect
			(at 0 0.889 270)
			(size 0.508 0.508)
			(layers "F.Cu" "F.Mask" "F.Paste")
			(net "GND")
		)
		(zone
			(layer "F.Cu")
			(hatch none 0.5)
			(connect_pads
				(clearance 0)
			)
			(min_thickness 0.25)
			(keepout
				(tracks not_allowed)
				(vias allowed)
				(pads allowed)
				(copperpour not_allowed)
				(footprints allowed)
			)
			(placement
				(enabled no)
				(sheetname "")
			)
			(fill
				(thermal_gap 0.5)
				(thermal_bridge_width 0.5)
				(island_removal_mode 0)
			)
			(polygon
				(pts
					(xy 180.4797 -76.77785) (xy 180.4797 -76.26985) (xy 180.8607 -76.26985) (xy 180.8607 -76.77785)
				)
			)
		)
		(zone
			(layer "F.Cu")
			(hatch none 0.5)
			(connect_pads
				(clearance 0)
			)
			(min_thickness 0.25)
			(keepout
				(tracks allowed)
				(vias not_allowed)
				(pads allowed)
				(copperpour not_allowed)
				(footprints allowed)
			)
			(placement
				(enabled no)
				(sheetname "")
			)
			(fill
				(thermal_gap 0.5)
				(thermal_bridge_width 0.5)
				(island_removal_mode 0)
			)
			(polygon
				(pts
					(xy 180.8607 -76.77785) (xy 180.8607 -76.26985) (xy 180.4797 -76.26985) (xy 180.4797 -76.77785)
				)
			)
		)
	)
	(footprint ""
		(layer "F.Cu")
		(at 407.399236 -47.889414 180)
		(property "Reference" "R25W66"
			(at -0.8382 -0.67818 180)
			(unlocked yes)
			(layer "F.SilkS")
			(effects
				(font
					(size 0.4064 0.254)
					(thickness 0.1524)
				)
				(justify left)
			)
		)
		(property "Value" ""
			(at 0 0 180)
			(layer "F.Fab")
			(effects
				(font
					(size 1.27 1.27)
				)
			)
		)
		(duplicate_pad_numbers_are_jumpers no)
		(fp_poly
			(pts
				(xy -0.2794 -0.1016) (xy 0.2794 -0.1016) (xy 0.2794 0.9906) (xy -0.2794 0.9906)
			)
			(stroke
				(width 0)
				(type default)
			)
			(fill no)
			(layer "F.CrtYd")
		)
		(fp_line
			(start 0.2794 0.9906)
			(end 0.2794 -0.1016)
			(stroke
				(width 0.1)
				(type default)
			)
			(layer "F.Fab")
		)
		(fp_line
			(start 0.2794 -0.1016)
			(end -0.2794 -0.1016)
			(stroke
				(width 0.1)
				(type default)
			)
			(layer "F.Fab")
		)
		(fp_line
			(start -0.2794 0.9906)
			(end 0.2794 0.9906)
			(stroke
				(width 0.1)
				(type default)
			)
			(layer "F.Fab")
		)
		(fp_line
			(start -0.2794 -0.1016)
			(end -0.2794 0.9906)
			(stroke
				(width 0.1)
				(type default)
			)
			(layer "F.Fab")
		)
		(pad "1" smd rect
			(at 0 0 180)
			(size 0.508 0.508)
			(layers "F.Cu" "F.Mask" "F.Paste")
			(net "CLK_24M_BMC_LPC")
		)
		(pad "2" smd rect
			(at 0 0.889 180)
			(size 0.508 0.508)
			(layers "F.Cu" "F.Mask" "F.Paste")
			(net "GND")
		)
		(zone
			(layer "F.Cu")
			(hatch none 0.5)
			(connect_pads
				(clearance 0)
			)
			(min_thickness 0.25)
			(keepout
				(tracks not_allowed)
				(vias allowed)
				(pads allowed)
				(copperpour not_allowed)
				(footprints allowed)
			)
			(placement
				(enabled no)
				(sheetname "")
			)
			(fill
				(thermal_gap 0.5)
				(thermal_bridge_width 0.5)
				(island_removal_mode 0)
			)
			(polygon
				(pts
					(xy 407.653236 -48.524414) (xy 407.145236 -48.524414) (xy 407.145236 -48.143414) (xy 407.653236 -48.143414)
				)
			)
		)
		(zone
			(layer "F.Cu")
			(hatch none 0.5)
			(connect_pads
				(clearance 0)
			)
			(min_thickness 0.25)
			(keepout
				(tracks allowed)
				(vias not_allowed)
				(pads allowed)
				(copperpour not_allowed)
				(footprints allowed)
			)
			(placement
				(enabled no)
				(sheetname "")
			)
			(fill
				(thermal_gap 0.5)
				(thermal_bridge_width 0.5)
				(island_removal_mode 0)
			)
			(polygon
				(pts
					(xy 407.653236 -48.143414) (xy 407.145236 -48.143414) (xy 407.145236 -48.524414) (xy 407.653236 -48.524414)
				)
			)
		)
	)
	(footprint ""
		(layer "F.Cu")
		(at 100.67544 -77.636116)
		(property "Reference" "C2D25"
			(at 0 0 0)
			(layer "F.SilkS")
			(hide yes)
			(effects
				(font
					(size 1.27 1.27)
				)
			)
		)
		(property "Value" ""
			(at 0 0 0)
			(layer "F.Fab")
			(effects
				(font
					(size 1.27 1.27)
				)
			)
		)
		(duplicate_pad_numbers_are_jumpers no)
		(fp_poly
			(pts
				(xy -0.4953 -0.2032) (xy 0.4953 -0.2032) (xy 0.4953 1.6002) (xy -0.4953 1.6002)
			)
			(stroke
				(width 0)
				(type default)
			)
			(fill no)
			(layer "F.CrtYd")
		)
		(fp_line
			(start -0.4953 -0.2032)
			(end 0.4953 -0.2032)
			(stroke
				(width 0.1)
				(type default)
			)
			(layer "F.Fab")
		)
		(fp_line
			(start -0.4953 1.6002)
			(end -0.4953 -0.2032)
			(stroke
				(width 0.1)
				(type default)
			)
			(layer "F.Fab")
		)
		(fp_line
			(start 0.4953 -0.2032)
			(end 0.4953 1.6002)
			(stroke
				(width 0.1)
				(type default)
			)
			(layer "F.Fab")
		)
		(fp_line
			(start 0.4953 1.6002)
			(end -0.4953 1.6002)
			(stroke
				(width 0.1)
				(type default)
			)
			(layer "F.Fab")
		)
		(pad "1" smd rect
			(at 0 0)
			(size 0.762 0.889)
			(layers "F.Cu" "F.Mask" "F.Paste")
			(net "PVCCIN_CPU1")
		)
		(pad "2" smd rect
			(at 0 1.397)
			(size 0.762 0.889)
			(layers "F.Cu" "F.Mask" "F.Paste")
			(net "GND")
		)
		(zone
			(layer "F.Cu")
			(hatch none 0.5)
			(connect_pads
				(clearance 0)
			)
			(min_thickness 0.25)
			(keepout
				(tracks not_allowed)
				(vias allowed)
				(pads allowed)
				(copperpour not_allowed)
				(footprints allowed)
			)
			(placement
				(enabled no)
				(sheetname "")
			)
			(fill
				(thermal_gap 0.5)
				(thermal_bridge_width 0.5)
				(island_removal_mode 0)
			)
			(polygon
				(pts
					(xy 100.29444 -77.191616) (xy 101.05644 -77.191616) (xy 101.05644 -76.683616) (xy 100.29444 -76.683616)
				)
			)
		)
	)
	(footprint ""
		(layer "F.Cu")
		(at 18.288 -98.7044 -90)
		(property "Reference" "R1C16"
			(at 0 0 270)
			(layer "F.SilkS")
			(hide yes)
			(effects
				(font
					(size 1.27 1.27)
				)
			)
		)
		(property "Value" ""
			(at 0 0 270)
			(layer "F.Fab")
			(effects
				(font
					(size 1.27 1.27)
				)
			)
		)
		(duplicate_pad_numbers_are_jumpers no)
		(fp_poly
			(pts
				(xy -0.2794 -0.1016) (xy 0.2794 -0.1016) (xy 0.2794 0.9906) (xy -0.2794 0.9906)
			)
			(stroke
				(width 0)
				(type default)
			)
			(fill no)
			(layer "F.CrtYd")
		)
		(fp_line
			(start -0.2794 0.9906)
			(end 0.2794 0.9906)
			(stroke
				(width 0.1)
				(type default)
			)
			(layer "F.Fab")
		)
		(fp_line
			(start 0.2794 0.9906)
			(end 0.2794 -0.1016)
			(stroke
				(width 0.1)
				(type default)
			)
			(layer "F.Fab")
		)
		(fp_line
			(start -0.2794 -0.1016)
			(end -0.2794 0.9906)
			(stroke
				(width 0.1)
				(type default)
			)
			(layer "F.Fab")
		)
		(fp_line
			(start 0.2794 -0.1016)
			(end -0.2794 -0.1016)
			(stroke
				(width 0.1)
				(type default)
			)
			(layer "F.Fab")
		)
		(pad "1" smd rect
			(at 0 0 270)
			(size 0.508 0.508)
			(layers "F.Cu" "F.Mask" "F.Paste")
			(net "VR_PVCCIN_CPU1_AVINSEN")
		)
		(pad "2" smd rect
			(at 0 0.889 270)
			(size 0.508 0.508)
			(layers "F.Cu" "F.Mask" "F.Paste")
			(net "GND")
		)
		(zone
			(layer "F.Cu")
			(hatch none 0.5)
			(connect_pads
				(clearance 0)
			)
			(min_thickness 0.25)
			(keepout
				(tracks not_allowed)
				(vias allowed)
				(pads allowed)
				(copperpour not_allowed)
				(footprints allowed)
			)
			(placement
				(enabled no)
				(sheetname "")
			)
			(fill
				(thermal_gap 0.5)
				(thermal_bridge_width 0.5)
				(island_removal_mode 0)
			)
			(polygon
				(pts
					(xy 17.653 -98.9584) (xy 17.653 -98.4504) (xy 18.034 -98.4504) (xy 18.034 -98.9584)
				)
			)
		)
		(zone
			(layer "F.Cu")
			(hatch none 0.5)
			(connect_pads
				(clearance 0)
			)
			(min_thickness 0.25)
			(keepout
				(tracks allowed)
				(vias not_allowed)
				(pads allowed)
				(copperpour not_allowed)
				(footprints allowed)
			)
			(placement
				(enabled no)
				(sheetname "")
			)
			(fill
				(thermal_gap 0.5)
				(thermal_bridge_width 0.5)
				(island_removal_mode 0)
			)
			(polygon
				(pts
					(xy 18.034 -98.9584) (xy 18.034 -98.4504) (xy 17.653 -98.4504) (xy 17.653 -98.9584)
				)
			)
		)
	)
)
